(kicad_pcb
	(version 20240108)
	(generator "pcbnew")
	(generator_version "8.0")
	(general
		(thickness 1.586)
		(legacy_teardrops no)
	)
	(paper "A4")
	(title_block
		(title "GMSL Serializer")
		(date "2024-11-27")
		(rev "1.1.1")
		(company "Antmicro Ltd")
		(comment 1 "www.antmicro.com")
		(comment 9 "footprints 59-62 of 117")
	)
	(layers
		(0 "F.Cu" signal)
		(1 "In1.Cu" power)
		(2 "In2.Cu" power)
		(31 "B.Cu" signal)
		(32 "B.Adhes" user "B.Adhesive")
		(33 "F.Adhes" user "F.Adhesive")
		(34 "B.Paste" user)
		(35 "F.Paste" user)
		(36 "B.SilkS" user "B.Silkscreen")
		(37 "F.SilkS" user "F.Silkscreen")
		(38 "B.Mask" user)
		(39 "F.Mask" user)
		(40 "Dwgs.User" user "User.Drawings")
		(41 "Cmts.User" user "User.Comments")
		(42 "Eco1.User" user "User.Eco1")
		(43 "Eco2.User" user "User.Eco2")
		(44 "Edge.Cuts" user)
		(45 "Margin" user)
		(46 "B.CrtYd" user "B.Courtyard")
		(47 "F.CrtYd" user "F.Courtyard")
		(48 "B.Fab" user)
		(49 "F.Fab" user)
	)
	(footprint "antmicro-footprints:C_0402_1005Metric"
		(layer "F.Cu")
		(at 150.45 98.025 45)
		(descr "Capacitor SMD 0402")
		(tags "capacitor SMD 0402")
		(property "Reference" "C31"
			(at 2.697612 0.420729 45)
			(layer "F.SilkS")
			(effects
				(font
					(size 0.7 0.7)
					(thickness 0.15)
				)
				(justify left bottom)
			)
		)
		(property "Value" "C_100n_0402"
			(at -1.022927 2.155213 45)
			(layer "F.Fab")
			(effects
				(font
					(size 0.7 0.7)
					(thickness 0.15)
				)
				(justify left bottom)
			)
		)
		(property "Footprint" "antmicro-footprints:C_0402_1005Metric"
			(at 0 0 45)
			(layer "F.Fab")
			(hide yes)
			(effects
				(font
					(size 1.27 1.27)
					(thickness 0.15)
				)
			)
		)
		(property "Datasheet" "https://www.murata.com/products/productdetail?partno=GRM155R61H104KE14%23"
			(at 0 0 45)
			(layer "F.Fab")
			(hide yes)
			(effects
				(font
					(size 1.27 1.27)
					(thickness 0.15)
				)
			)
		)
		(property "Author" "Antmicro"
			(at 113.379927 -77.673358 0)
			(layer "F.Fab")
			(hide yes)
			(effects
				(font
					(size 1 1)
					(thickness 0.15)
				)
			)
		)
		(property "Dielectric" "X5R"
			(at 113.379927 -77.673358 0)
			(layer "F.Fab")
			(hide yes)
			(effects
				(font
					(size 1 1)
					(thickness 0.15)
				)
			)
		)
		(property "License" "Apache-2.0"
			(at 113.379927 -77.673358 0)
			(layer "F.Fab")
			(hide yes)
			(effects
				(font
					(size 1 1)
					(thickness 0.15)
				)
			)
		)
		(property "MPN" "GRM155R61H104KE14D"
			(at 113.379927 -77.673358 0)
			(layer "F.Fab")
			(hide yes)
			(effects
				(font
					(size 1 1)
					(thickness 0.15)
				)
			)
		)
		(property "Manufacturer" "Murata"
			(at 113.379927 -77.673358 0)
			(layer "F.Fab")
			(hide yes)
			(effects
				(font
					(size 1 1)
					(thickness 0.15)
				)
			)
		)
		(property "Val" "100n"
			(at 113.379927 -77.673358 0)
			(layer "F.Fab")
			(hide yes)
			(effects
				(font
					(size 1 1)
					(thickness 0.15)
				)
			)
		)
		(property "Voltage" "50V"
			(at 113.379927 -77.673358 0)
			(layer "F.Fab")
			(hide yes)
			(effects
				(font
					(size 1 1)
					(thickness 0.15)
				)
			)
		)
		(sheetname "Serializer")
		(sheetfile "serializer.kicad_sch")
		(attr smd)
		(fp_poly
			(pts
				(xy -0.925 -0.47) (xy 0.925 -0.47) (xy 0.925 0.47) (xy -0.925 0.47)
			)
			(stroke
				(width 0.05)
				(type default)
			)
			(fill none)
			(layer "F.CrtYd")
		)
		(fp_line
			(start -0.494 -0.25)
			(end 0.504 -0.25)
			(stroke
				(width 0.15)
				(type solid)
			)
			(layer "F.Fab")
		)
		(fp_line
			(start -0.494 0.248)
			(end -0.494 -0.25)
			(stroke
				(width 0.15)
				(type solid)
			)
			(layer "F.Fab")
		)
		(fp_line
			(start 0.504 -0.25)
			(end 0.504 0.248)
			(stroke
				(width 0.15)
				(type solid)
			)
			(layer "F.Fab")
		)
		(fp_line
			(start 0.504 0.248)
			(end -0.494 0.248)
			(stroke
				(width 0.15)
				(type solid)
			)
			(layer "F.Fab")
		)
		(fp_text user "${REFERENCE}"
			(at -0.939 4.599 45)
			(layer "F.Fab")
			(hide yes)
			(effects
				(font
					(size 0.7 0.7)
					(thickness 0.15)
				)
				(justify left bottom)
			)
		)
		(fp_text user "Author: Antmicro"
			(at -0.939 3.399 45)
			(layer "F.Fab")
			(hide yes)
			(effects
				(font
					(size 0.7 0.7)
					(thickness 0.15)
				)
				(justify left bottom)
			)
		)
		(fp_text user "License: Apache-2.0"
			(at -0.939 5.799 45)
			(layer "F.Fab")
			(hide yes)
			(effects
				(font
					(size 0.7 0.7)
					(thickness 0.15)
				)
				(justify left bottom)
			)
		)
		(pad "1" smd roundrect
			(at -0.48 0 45)
			(size 0.59 0.64)
			(layers "F.Cu" "F.Paste" "F.Mask")
			(roundrect_rratio 0.25)
			(net 33 "Net-(U6-SION)")
			(pintype "passive")
		)
		(pad "2" smd roundrect
			(at 0.48 0 45)
			(size 0.59 0.64)
			(layers "F.Cu" "F.Paste" "F.Mask")
			(roundrect_rratio 0.25)
			(net 16 "Net-(C31-Pad2)")
			(pintype "passive")
		)
	)
	(footprint "antmicro-footprints:TSOT23-6"
		(layer "F.Cu")
		(at 133.779 83.45 180)
		(property "Reference" "U1"
			(at -0.722 1.766 0)
			(layer "F.SilkS")
			(effects
				(font
					(size 0.7 0.7)
					(thickness 0.15)
				)
				(justify right bottom)
			)
		)
		(property "Value" "AP62301_TSOT"
			(at -1.44 3.9 0)
			(layer "F.Fab")
			(effects
				(font
					(size 0.7 0.7)
					(thickness 0.15)
				)
				(justify right bottom)
			)
		)
		(property "Footprint" "antmicro-footprints:TSOT23-6"
			(at 0 0 180)
			(layer "F.Fab")
			(hide yes)
			(effects
				(font
					(size 1.27 1.27)
					(thickness 0.15)
				)
			)
		)
		(property "Datasheet" "https://www.diodes.com/assets/Datasheets/AP62300_AP62301_AP62300T.pdf"
			(at 0 0 180)
			(layer "F.Fab")
			(hide yes)
			(effects
				(font
					(size 1.27 1.27)
					(thickness 0.15)
				)
			)
		)
		(property "Author" "Antmicro"
			(at 271.098 166.6 0)
			(layer "F.Fab")
			(hide yes)
			(effects
				(font
					(size 1 1)
					(thickness 0.15)
				)
			)
		)
		(property "License" "Apache-2.0"
			(at 271.098 166.6 0)
			(layer "F.Fab")
			(hide yes)
			(effects
				(font
					(size 1 1)
					(thickness 0.15)
				)
			)
		)
		(property "MPN" "AP62301WU-7"
			(at 271.098 166.6 0)
			(layer "F.Fab")
			(hide yes)
			(effects
				(font
					(size 1 1)
					(thickness 0.15)
				)
			)
		)
		(property "Manufacturer" "Diodes Incorporated"
			(at 271.098 166.6 0)
			(layer "F.Fab")
			(hide yes)
			(effects
				(font
					(size 1 1)
					(thickness 0.15)
				)
			)
		)
		(sheetname "Supply")
		(sheetfile "supply.kicad_sch")
		(attr smd)
		(fp_line
			(start 1 1.55)
			(end 1 1.4)
			(stroke
				(width 0.15)
				(type solid)
			)
			(layer "F.SilkS")
		)
		(fp_line
			(start 1 1.55)
			(end -1 1.55)
			(stroke
				(width 0.15)
				(type solid)
			)
			(layer "F.SilkS")
		)
		(fp_line
			(start 1 -1.497)
			(end 1 -1.375)
			(stroke
				(width 0.15)
				(type solid)
			)
			(layer "F.SilkS")
		)
		(fp_line
			(start 1 -1.497)
			(end -1 -1.5)
			(stroke
				(width 0.15)
				(type solid)
			)
			(layer "F.SilkS")
		)
		(fp_line
			(start -1 1.55)
			(end -1 1.4)
			(stroke
				(width 0.15)
				(type solid)
			)
			(layer "F.SilkS")
		)
		(fp_line
			(start -1 -1.5)
			(end -1 -1.375)
			(stroke
				(width 0.15)
				(type solid)
			)
			(layer "F.SilkS")
		)
		(fp_circle
			(center -1.44 -1.5)
			(end -1.39 -1.5)
			(stroke
				(width 0.15)
				(type solid)
			)
			(fill solid)
			(layer "F.SilkS")
		)
		(fp_rect
			(start 1.93 -1.7)
			(end -1.93 1.7)
			(stroke
				(width 0.05)
				(type solid)
			)
			(fill none)
			(layer "F.CrtYd")
		)
		(fp_line
			(start -0.45 -1.521)
			(end -0.876 -1.096)
			(stroke
				(width 0.15)
				(type solid)
			)
			(layer "F.Fab")
		)
		(fp_rect
			(start 0.875 1.528)
			(end -0.875 -1.525)
			(stroke
				(width 0.15)
				(type solid)
			)
			(fill none)
			(layer "F.Fab")
		)
		(fp_text user "License: Apache-2.0"
			(at -1.93 6.199 0)
			(layer "F.Fab")
			(hide yes)
			(effects
				(font
					(size 0.7 0.7)
					(thickness 0.15)
				)
				(justify right bottom)
			)
		)
		(fp_text user "Author: Antmicro"
			(at -1.93 5 0)
			(layer "F.Fab")
			(hide yes)
			(effects
				(font
					(size 0.7 0.7)
					(thickness 0.15)
				)
				(justify right bottom)
			)
		)
		(fp_text user "${REFERENCE}"
			(at -1.93 3.8 0)
			(layer "F.Fab")
			(hide yes)
			(effects
				(font
					(size 0.7 0.7)
					(thickness 0.15)
				)
				(justify right bottom)
			)
		)
		(pad "1" smd rect
			(at -1.301 -0.947 90)
			(size 0.7 1.2)
			(layers "F.Cu" "F.Paste" "F.Mask")
			(net 1 "GND")
			(pinfunction "GND")
			(pintype "power_in")
		)
		(pad "2" smd rect
			(at -1.301 0.004 90)
			(size 0.7 1.2)
			(layers "F.Cu" "F.Paste" "F.Mask")
			(net 4 "/Supply/SW_5V")
			(pinfunction "SW")
			(pintype "power_out")
		)
		(pad "3" smd rect
			(at -1.301 0.954 90)
			(size 0.7 1.2)
			(layers "F.Cu" "F.Paste" "F.Mask")
			(net 2 "+12V")
			(pinfunction "VIN")
			(pintype "power_in")
		)
		(pad "4" smd rect
			(at 1.299 0.954 90)
			(size 0.7 1.2)
			(layers "F.Cu" "F.Paste" "F.Mask")
			(net 64 "/Supply/FB_5V")
			(pinfunction "FB")
			(pintype "input")
		)
		(pad "5" smd rect
			(at 1.299 0.004 90)
			(size 0.7 1.2)
			(layers "F.Cu" "F.Paste" "F.Mask")
			(net 62 "/Supply/EN_5V")
			(pinfunction "EN")
			(pintype "input")
		)
		(pad "6" smd rect
			(at 1.299 -0.947 90)
			(size 0.7 1.2)
			(layers "F.Cu" "F.Paste" "F.Mask")
			(net 3 "Net-(U1-BST)")
			(pinfunction "BST")
			(pintype "output")
		)
	)
	(footprint "antmicro-footprints:R_0402_1005Metric"
		(layer "F.Cu")
		(at 138.35 115.525 90)
		(descr "Resistor SMD 0402")
		(tags "resistor SMD 0402")
		(property "Reference" "R40"
			(at 0.875 0.45 90)
			(layer "F.SilkS")
			(effects
				(font
					(size 0.7 0.7)
					(thickness 0.15)
				)
				(justify left bottom)
			)
		)
		(property "Value" "R_1k65_0402"
			(at -1.011843 1.772047 90)
			(layer "F.Fab")
			(effects
				(font
					(size 0.7 0.7)
					(thickness 0.15)
				)
				(justify left bottom)
			)
		)
		(property "Footprint" "antmicro-footprints:R_0402_1005Metric"
			(at 0 0 90)
			(layer "F.Fab")
			(hide yes)
			(effects
				(font
					(size 1.27 1.27)
					(thickness 0.15)
				)
			)
		)
		(property "Datasheet" "https://www.farnell.com/datasheets/3795017.pdf"
			(at 0 0 90)
			(layer "F.Fab")
			(hide yes)
			(effects
				(font
					(size 1.27 1.27)
					(thickness 0.15)
				)
			)
		)
		(property "Author" "Antmicro"
			(at 253.875 -22.825 0)
			(layer "F.Fab")
			(hide yes)
			(effects
				(font
					(size 1 1)
					(thickness 0.15)
				)
			)
		)
		(property "License" "Apache-2.0"
			(at 253.875 -22.825 0)
			(layer "F.Fab")
			(hide yes)
			(effects
				(font
					(size 1 1)
					(thickness 0.15)
				)
			)
		)
		(property "MPN" "RC0402FR-071K65L"
			(at 253.875 -22.825 0)
			(layer "F.Fab")
			(hide yes)
			(effects
				(font
					(size 1 1)
					(thickness 0.15)
				)
			)
		)
		(property "Manufacturer" "YAGEO"
			(at 253.875 -22.825 0)
			(layer "F.Fab")
			(hide yes)
			(effects
				(font
					(size 1 1)
					(thickness 0.15)
				)
			)
		)
		(property "Public" ""
			(at 253.875 -22.825 0)
			(layer "F.Fab")
			(hide yes)
			(effects
				(font
					(size 1 1)
					(thickness 0.15)
				)
			)
		)
		(property "Tolerance" "1%"
			(at 253.875 -22.825 0)
			(layer "F.Fab")
			(hide yes)
			(effects
				(font
					(size 1 1)
					(thickness 0.15)
				)
			)
		)
		(property "Val" "1k65"
			(at 253.875 -22.825 0)
			(layer "F.Fab")
			(hide yes)
			(effects
				(font
					(size 1 1)
					(thickness 0.15)
				)
			)
		)
		(sheetname "Supply")
		(sheetfile "supply.kicad_sch")
		(attr smd)
		(fp_rect
			(start -0.925 -0.47)
			(end 0.925 0.47)
			(stroke
				(width 0.05)
				(type default)
			)
			(fill none)
			(layer "F.CrtYd")
		)
		(fp_rect
			(start -0.5 -0.25)
			(end 0.5 0.25)
			(stroke
				(width 0.15)
				(type solid)
			)
			(fill none)
			(layer "F.Fab")
		)
		(fp_text user "License: Apache-2.0"
			(at -0.95 5.169 90)
			(layer "F.Fab")
			(hide yes)
			(effects
				(font
					(size 0.7 0.7)
					(thickness 0.15)
				)
				(justify left bottom)
			)
		)
		(fp_text user "${REFERENCE}"
			(at -0.95 3.168 90)
			(layer "F.Fab")
			(hide yes)
			(effects
				(font
					(size 0.7 0.7)
					(thickness 0.15)
				)
				(justify left bottom)
			)
		)
		(fp_text user "Author: Antmicro"
			(at -0.95 4.169 90)
			(layer "F.Fab")
			(hide yes)
			(effects
				(font
					(size 0.7 0.7)
					(thickness 0.15)
				)
				(justify left bottom)
			)
		)
		(pad "1" smd roundrect
			(at -0.48 0 90)
			(size 0.59 0.64)
			(layers "F.Cu" "F.Paste" "F.Mask")
			(roundrect_rratio 0.25)
			(net 1 "GND")
			(pintype "passive")
		)
		(pad "2" smd roundrect
			(at 0.48 0 90)
			(size 0.59 0.64)
			(layers "F.Cu" "F.Paste" "F.Mask")
			(roundrect_rratio 0.25)
			(net 75 "Net-(D9-C)")
			(pintype "passive")
		)
	)
	(footprint "antmicro-footprints:L_0806_2016Metric"
		(layer "F.Cu")
		(at 161.6 103.8)
		(property "Reference" "L2"
			(at -0.75 1.9 0)
			(layer "F.SilkS")
			(effects
				(font
					(size 0.7 0.7)
					(thickness 0.15)
				)
				(justify left bottom)
			)
		)
		(property "Value" "L_1u_2.6A_0806"
			(at 0 2 0)
			(layer "F.Fab")
			(effects
				(font
					(size 0.7 0.7)
					(thickness 0.15)
				)
				(justify left bottom)
			)
		)
		(property "Footprint" "antmicro-footprints:L_0806_2016Metric"
			(at 0 0 0)
			(layer "F.Fab")
			(hide yes)
			(effects
				(font
					(size 1.27 1.27)
					(thickness 0.15)
				)
			)
		)
		(property "Datasheet" "https://www.bourns.com/docs/Product-Datasheets/SRP2010.pdf"
			(at 0 0 0)
			(layer "F.Fab")
			(hide yes)
			(effects
				(font
					(size 1.27 1.27)
					(thickness 0.15)
				)
			)
		)
		(property "Author" "Antmicro"
			(at 0 0 0)
			(layer "F.Fab")
			(hide yes)
			(effects
				(font
					(size 1 1)
					(thickness 0.15)
				)
			)
		)
		(property "IMax" "2.6 A"
			(at 0 0 0)
			(layer "F.Fab")
			(hide yes)
			(effects
				(font
					(size 1 1)
					(thickness 0.15)
				)
			)
		)
		(property "ISat" "2.9 A"
			(at 0 0 0)
			(layer "F.Fab")
			(hide yes)
			(effects
				(font
					(size 1 1)
					(thickness 0.15)
				)
			)
		)
		(property "License" "Apache-2.0"
			(at 0 0 0)
			(layer "F.Fab")
			(hide yes)
			(effects
				(font
					(size 1 1)
					(thickness 0.15)
				)
			)
		)
		(property "MPN" "SRP2010-1R0M"
			(at 0 0 0)
			(layer "F.Fab")
			(hide yes)
			(effects
				(font
					(size 1 1)
					(thickness 0.15)
				)
			)
		)
		(property "Manufacturer" "Bourns"
			(at 0 0 0)
			(layer "F.Fab")
			(hide yes)
			(effects
				(font
					(size 1 1)
					(thickness 0.15)
				)
			)
		)
		(property "Size" "2.0x1.6"
			(at 0 0 0)
			(layer "F.Fab")
			(hide yes)
			(effects
				(font
					(size 1 1)
					(thickness 0.15)
				)
			)
		)
		(property "Val" "1u/2.6A"
			(at 0 0 0)
			(layer "F.Fab")
			(hide yes)
			(effects
				(font
					(size 1 1)
					(thickness 0.15)
				)
			)
		)
		(sheetname "Supply")
		(sheetfile "supply.kicad_sch")
		(attr smd)
		(fp_line
			(start -0.301 0.9)
			(end 0.299 0.9)
			(stroke
				(width 0.15)
				(type solid)
			)
			(layer "F.SilkS")
		)
		(fp_line
			(start -0.3 -0.9)
			(end 0.298 -0.9)
			(stroke
				(width 0.15)
				(type solid)
			)
			(layer "F.SilkS")
		)
		(fp_rect
			(start -1.75 -1.05)
			(end 1.75 1.05)
			(stroke
				(width 0.05)
				(type solid)
			)
			(fill none)
			(layer "F.CrtYd")
		)
		(fp_rect
			(start -0.951 -0.882)
			(end 0.949 0.875)
			(stroke
				(width 0.15)
				(type solid)
			)
			(fill none)
			(layer "F.Fab")
		)
		(fp_text user "Author: Antmicro"
			(at -1.9 4.4 0)
			(layer "F.Fab")
			(hide yes)
			(effects
				(font
					(size 0.7 0.7)
					(thickness 0.15)
				)
				(justify left bottom)
			)
		)
		(fp_text user "${REFERENCE}"
			(at -1.9 3.1 0)
			(layer "F.Fab")
			(hide yes)
			(effects
				(font
					(size 0.7 0.7)
					(thickness 0.15)
				)
				(justify left bottom)
			)
		)
		(fp_text user "License: Apache-2.0"
			(at -1.9 5.75 0)
			(layer "F.Fab")
			(hide yes)
			(effects
				(font
					(size 0.7 0.7)
					(thickness 0.15)
				)
				(justify left bottom)
			)
		)
		(pad "1" smd roundrect
			(at -1.1 -0.001)
			(size 1 1.8)
			(layers "F.Cu" "F.Paste" "F.Mask")
			(roundrect_rratio 0.15)
			(net 6 "/Supply/SW_1V8")
			(pintype "passive")
		)
		(pad "2" smd roundrect
			(at 1.1 -0.001)
			(size 1 1.8)
			(layers "F.Cu" "F.Paste" "F.Mask")
			(roundrect_rratio 0.15)
			(net 8 "/Supply/OUT_1V8")
			(pintype "passive")
		)
	)
)
